(kicad_pcb
	(version 20260206)
	(generator "pcbnew")
	(generator_version "10.0")
	(general
		(thickness 1.6)
		(legacy_teardrops no)
	)
	(paper "A4")
	(title_block
		(title "baseboard — 13948-1b.1110WZS1818.brd")
		(comment 1 "Honey Badger (Wiwynn) / footprints 962-968 of 2523")
	)
	(layers
		(0 "F.Cu" signal "TOP")
		(4 "In1.Cu" signal "L2GND")
		(6 "In2.Cu" signal "L3")
		(8 "In3.Cu" signal "L4VCC")
		(10 "In4.Cu" signal "L5VCC")
		(12 "In5.Cu" signal "L6")
		(14 "In6.Cu" signal "L7GND")
		(2 "B.Cu" signal "BOTTOM")
		(9 "F.Adhes" user "F.Adhesive")
		(11 "B.Adhes" user "B.Adhesive")
		(13 "F.Paste" user "Package Geometry/Pastemask Top")
		(15 "B.Paste" user "Package Geometry/Pastemask Bottom")
		(5 "F.SilkS" user "Ref Des/Silkscreen Top")
		(7 "B.SilkS" user "Ref Des/Silkscreen Bottom")
		(1 "F.Mask" user "Board Geometry/Soldermask Top")
		(3 "B.Mask" user "Board Geometry/Soldermask Bottom")
		(17 "Dwgs.User" user "User.Drawings")
		(19 "Cmts.User" user "User.Comments")
		(21 "Eco1.User" user "User.Eco1")
		(23 "Eco2.User" user "User.Eco2")
		(25 "Edge.Cuts" user "Board Geometry/Outline")
		(27 "Margin" user)
		(31 "F.CrtYd" user "Package Geometry/Place Bound Top")
		(29 "B.CrtYd" user "Package Geometry/Place Bound Bottom")
		(35 "F.Fab" user "Ref Des/Assembly Top")
		(33 "B.Fab" user "Ref Des/Assembly Bottom")
	)
	(footprint ""
		(layer "F.Cu")
		(at 282.829 -71.12 90)
		(property "Reference" "C267"
			(at 0 0 90)
			(layer "F.SilkS")
			(hide yes)
			(effects
				(font
					(size 1.27 1.27)
				)
			)
		)
		(property "Value" "SCD1U25V3KX-GP"
			(at 0 -2.8194 90)
			(unlocked yes)
			(layer "F.Fab")
			(hide yes)
			(effects
				(font
					(size 1.016 1.016)
					(thickness 0.1524)
				)
			)
		)
		(property "Device Type" "C603H36"
			(at 0 -4.3434 90)
			(unlocked yes)
			(layer "F.Fab")
			(hide yes)
			(effects
				(font
					(size 1.016 1.016)
					(thickness 0.1524)
				)
			)
		)
		(duplicate_pad_numbers_are_jumpers no)
		(fp_line
			(start 0.508 0)
			(end -0.508 0)
			(stroke
				(width 0.2032)
				(type default)
			)
			(layer "F.SilkS")
		)
		(fp_rect
			(start -0.5842 1.3335)
			(end 0.5842 -1.3335)
			(stroke
				(width 0)
				(type default)
			)
			(fill no)
			(layer "F.CrtYd")
		)
		(fp_rect
			(start -0.5842 1.3335)
			(end 0.5842 -1.3335)
			(stroke
				(width 0)
				(type default)
			)
			(fill no)
			(layer "F.Fab")
		)
		(pad "1" smd custom
			(at 0 -0.762 90)
			(size 0.2159 0.2159)
			(layers "F.Cu" "F.Mask" "F.Paste")
			(net "P12V_PCIE")
			(options
				(clearance outline)
				(anchor circle)
			)
			(primitives
				(gr_poly
					(pts
						(arc
							(start -0.3302 -0.4318)
							(mid -0.402042 -0.402042)
							(end -0.4318 -0.3302)
						)
						(arc
							(start -0.4318 0.3302)
							(mid -0.402042 0.402042)
							(end -0.3302 0.4318)
						)
						(arc
							(start 0.3302 0.4318)
							(mid 0.402042 0.402042)
							(end 0.4318 0.3302)
						)
						(arc
							(start 0.4318 -0.3302)
							(mid 0.402042 -0.402042)
							(end 0.3302 -0.4318)
						)
					)
					(width 0)
					(fill yes)
				)
			)
		)
		(pad "2" smd custom
			(at 0 0.762 90)
			(size 0.2159 0.2159)
			(layers "F.Cu" "F.Mask" "F.Paste")
			(net "GND")
			(options
				(clearance outline)
				(anchor circle)
			)
			(primitives
				(gr_poly
					(pts
						(arc
							(start -0.3302 -0.4318)
							(mid -0.402042 -0.402042)
							(end -0.4318 -0.3302)
						)
						(arc
							(start -0.4318 0.3302)
							(mid -0.402042 0.402042)
							(end -0.3302 0.4318)
						)
						(arc
							(start 0.3302 0.4318)
							(mid 0.402042 0.402042)
							(end 0.4318 0.3302)
						)
						(arc
							(start 0.4318 -0.3302)
							(mid 0.402042 -0.402042)
							(end 0.3302 -0.4318)
						)
					)
					(width 0)
					(fill yes)
				)
			)
		)
	)
	(footprint ""
		(layer "F.Cu")
		(at 80.499966 -83.439 -90)
		(property "Reference" "SL14"
			(at 0 0 270)
			(layer "F.SilkS")
			(hide yes)
			(effects
				(font
					(size 1.27 1.27)
				)
			)
		)
		(property "Value" "MPZ2012S601AT-GP"
			(at 0 -4.2418 270)
			(unlocked yes)
			(layer "F.Fab")
			(hide yes)
			(effects
				(font
					(size 1.016 1.016)
					(thickness 0.1524)
				)
			)
		)
		(property "Device Type" "L805H42"
			(at 0 -5.7912 270)
			(unlocked yes)
			(layer "F.Fab")
			(hide yes)
			(effects
				(font
					(size 1.016 1.016)
					(thickness 0.1524)
				)
			)
		)
		(duplicate_pad_numbers_are_jumpers no)
		(fp_line
			(start -0.889 1.7018)
			(end -0.889 -1.7018)
			(stroke
				(width 0.1524)
				(type default)
			)
			(layer "F.SilkS")
		)
		(fp_line
			(start 0.889 1.7018)
			(end -0.889 1.7018)
			(stroke
				(width 0.1524)
				(type default)
			)
			(layer "F.SilkS")
		)
		(fp_line
			(start -0.889 -1.7018)
			(end 0.889 -1.7018)
			(stroke
				(width 0.1524)
				(type default)
			)
			(layer "F.SilkS")
		)
		(fp_line
			(start 0.889 -1.7018)
			(end 0.889 1.7018)
			(stroke
				(width 0.1524)
				(type default)
			)
			(layer "F.SilkS")
		)
		(fp_rect
			(start -0.9652 1.778)
			(end 0.9652 -1.778)
			(stroke
				(width 0)
				(type default)
			)
			(fill no)
			(layer "F.CrtYd")
		)
		(fp_rect
			(start -0.9652 1.778)
			(end 0.9652 -1.778)
			(stroke
				(width 0)
				(type default)
			)
			(fill no)
			(layer "F.Fab")
		)
		(pad "1" smd rect
			(at 0 -0.9652 270)
			(size 1.397 1.143)
			(layers "F.Cu" "F.Mask" "F.Paste")
			(net "PLLDDR_VDDA18")
		)
		(pad "2" smd rect
			(at 0 0.9652 270)
			(size 1.397 1.143)
			(layers "F.Cu" "F.Mask" "F.Paste")
			(net "P1V8_E")
		)
	)
	(footprint ""
		(layer "F.Cu")
		(at 336.296 -13.462 180)
		(property "Reference" "SLED28"
			(at 0 0 180)
			(layer "F.SilkS")
			(hide yes)
			(effects
				(font
					(size 1.27 1.27)
				)
			)
		)
		(property "Value" "LED-YG-51-GP"
			(at -2.6924 -1.4224 180)
			(unlocked yes)
			(layer "F.Fab")
			(hide yes)
			(effects
				(font
					(size 1.016 1.016)
					(thickness 0.1524)
				)
			)
		)
		(property "Device Type" "LED1608AKH40"
			(at -2.6924 -2.9464 180)
			(unlocked yes)
			(layer "F.Fab")
			(hide yes)
			(effects
				(font
					(size 1.016 1.016)
					(thickness 0.1524)
				)
			)
		)
		(duplicate_pad_numbers_are_jumpers no)
		(fp_line
			(start 0.7493 1.651)
			(end 0.7493 1.1811)
			(stroke
				(width 0.3302)
				(type default)
			)
			(layer "F.SilkS")
		)
		(fp_line
			(start 0.6604 1.3716)
			(end -0.6604 1.3716)
			(stroke
				(width 0.1524)
				(type default)
			)
			(layer "F.SilkS")
		)
		(fp_line
			(start 0.6604 -1.3716)
			(end 0.6604 1.3716)
			(stroke
				(width 0.1524)
				(type default)
			)
			(layer "F.SilkS")
		)
		(fp_line
			(start -0.5969 1.5494)
			(end 0.5842 1.5494)
			(stroke
				(width 0.508)
				(type default)
			)
			(layer "F.SilkS")
		)
		(fp_line
			(start -0.6604 1.3716)
			(end -0.6604 -1.3716)
			(stroke
				(width 0.1524)
				(type default)
			)
			(layer "F.SilkS")
		)
		(fp_line
			(start -0.6604 -1.3716)
			(end 0.6604 -1.3716)
			(stroke
				(width 0.1524)
				(type default)
			)
			(layer "F.SilkS")
		)
		(fp_line
			(start -0.7493 1.651)
			(end -0.7493 1.1811)
			(stroke
				(width 0.3302)
				(type default)
			)
			(layer "F.SilkS")
		)
		(fp_rect
			(start -0.6223 1.3335)
			(end 0.6223 -1.3335)
			(stroke
				(width 0)
				(type default)
			)
			(fill no)
			(layer "F.CrtYd")
		)
		(fp_rect
			(start -0.6223 1.3335)
			(end 0.6223 -1.3335)
			(stroke
				(width 0)
				(type default)
			)
			(fill no)
			(layer "F.Fab")
		)
		(pad "A" smd custom
			(at 0 -0.762 180)
			(size 0.2159 0.2159)
			(layers "F.Cu" "F.Mask" "F.Paste")
			(net "EXP_BMC_HB_LED_R")
			(options
				(clearance outline)
				(anchor circle)
			)
			(primitives
				(gr_poly
					(pts
						(arc
							(start -0.3302 -0.4318)
							(mid -0.402042 -0.402042)
							(end -0.4318 -0.3302)
						)
						(arc
							(start -0.4318 0.3302)
							(mid -0.402042 0.402042)
							(end -0.3302 0.4318)
						)
						(arc
							(start 0.3302 0.4318)
							(mid 0.402042 0.402042)
							(end 0.4318 0.3302)
						)
						(arc
							(start 0.4318 -0.3302)
							(mid 0.402042 -0.402042)
							(end 0.3302 -0.4318)
						)
					)
					(width 0)
					(fill yes)
				)
			)
		)
		(pad "K" smd custom
			(at 0 0.762 180)
			(size 0.2159 0.2159)
			(layers "F.Cu" "F.Mask" "F.Paste")
			(net "EXP_BMC_HB_LED_D")
			(options
				(clearance outline)
				(anchor circle)
			)
			(primitives
				(gr_poly
					(pts
						(arc
							(start -0.3302 -0.4318)
							(mid -0.402042 -0.402042)
							(end -0.4318 -0.3302)
						)
						(arc
							(start -0.4318 0.3302)
							(mid -0.402042 0.402042)
							(end -0.3302 0.4318)
						)
						(arc
							(start 0.3302 0.4318)
							(mid 0.402042 0.402042)
							(end 0.4318 0.3302)
						)
						(arc
							(start 0.4318 -0.3302)
							(mid 0.402042 -0.402042)
							(end 0.3302 -0.4318)
						)
					)
					(width 0)
					(fill yes)
				)
			)
		)
	)
	(footprint ""
		(layer "F.Cu")
		(at 267.772896 -75.223624 90)
		(property "Reference" "C261"
			(at 0 0 90)
			(layer "F.SilkS")
			(hide yes)
			(effects
				(font
					(size 1.27 1.27)
				)
			)
		)
		(property "Value" "SCD1U25V2KX-2-GP"
			(at 1.1811 -2.7051 90)
			(unlocked yes)
			(layer "F.Fab")
			(hide yes)
			(effects
				(font
					(size 1.016 1.016)
					(thickness 0.1524)
				)
			)
		)
		(property "Device Type" "C402H22"
			(at 1.1811 -4.2291 90)
			(unlocked yes)
			(layer "F.Fab")
			(hide yes)
			(effects
				(font
					(size 1.016 1.016)
					(thickness 0.1524)
				)
			)
		)
		(duplicate_pad_numbers_are_jumpers no)
		(fp_rect
			(start -0.4318 0.9525)
			(end 0.4318 -0.9525)
			(stroke
				(width 0)
				(type default)
			)
			(fill no)
			(layer "F.CrtYd")
		)
		(fp_rect
			(start -0.4318 0.9525)
			(end 0.4318 -0.9525)
			(stroke
				(width 0)
				(type default)
			)
			(fill no)
			(layer "F.Fab")
		)
		(pad "1" smd custom
			(at 0 -0.4445 90)
			(size 0.1524 0.1524)
			(layers "F.Cu" "F.Mask" "F.Paste")
			(net "P12V_MSB")
			(options
				(clearance outline)
				(anchor circle)
			)
			(primitives
				(gr_poly
					(pts
						(arc
							(start 0.3048 -0.2032)
							(mid 0.275042 -0.275042)
							(end 0.2032 -0.3048)
						)
						(arc
							(start -0.2032 -0.3048)
							(mid -0.275042 -0.275042)
							(end -0.3048 -0.2032)
						)
						(arc
							(start -0.3048 0.2032)
							(mid -0.275042 0.275042)
							(end -0.2032 0.3048)
						)
						(arc
							(start 0.2032 0.3048)
							(mid 0.275042 0.275042)
							(end 0.3048 0.2032)
						)
					)
					(width 0)
					(fill yes)
				)
			)
		)
		(pad "2" smd custom
			(at 0 0.4445 90)
			(size 0.1524 0.1524)
			(layers "F.Cu" "F.Mask" "F.Paste")
			(net "GND")
			(options
				(clearance outline)
				(anchor circle)
			)
			(primitives
				(gr_poly
					(pts
						(arc
							(start 0.3048 -0.2032)
							(mid 0.275042 -0.275042)
							(end 0.2032 -0.3048)
						)
						(arc
							(start -0.2032 -0.3048)
							(mid -0.275042 -0.275042)
							(end -0.3048 -0.2032)
						)
						(arc
							(start -0.3048 0.2032)
							(mid -0.275042 0.275042)
							(end -0.2032 0.3048)
						)
						(arc
							(start 0.2032 0.3048)
							(mid 0.275042 0.275042)
							(end 0.3048 0.2032)
						)
					)
					(width 0)
					(fill yes)
				)
			)
		)
	)
	(footprint ""
		(layer "F.Cu")
		(at 39.0652 -119.3292 90)
		(property "Reference" "SR841"
			(at 0 0 90)
			(layer "F.SilkS")
			(hide yes)
			(effects
				(font
					(size 1.27 1.27)
				)
			)
		)
		(property "Value" "10KR2F-2-GP"
			(at 0.064008 -3.993896 90)
			(unlocked yes)
			(layer "F.Fab")
			(hide yes)
			(effects
				(font
					(size 1.016 1.016)
					(thickness 0.1524)
				)
			)
		)
		(property "Device Type" "R402H16"
			(at 0.064008 -5.517896 90)
			(unlocked yes)
			(layer "F.Fab")
			(hide yes)
			(effects
				(font
					(size 1.016 1.016)
					(thickness 0.1524)
				)
			)
		)
		(duplicate_pad_numbers_are_jumpers no)
		(fp_line
			(start 0.508 -0.9398)
			(end -0.508 -0.9398)
			(stroke
				(width 0.1524)
				(type default)
			)
			(layer "F.SilkS")
		)
		(fp_line
			(start -0.508 -0.9398)
			(end -0.508 0.9398)
			(stroke
				(width 0.1524)
				(type default)
			)
			(layer "F.SilkS")
		)
		(fp_rect
			(start -0.508 0.9398)
			(end 0.508 -0.9398)
			(stroke
				(width 0)
				(type default)
			)
			(fill no)
			(layer "F.CrtYd")
		)
		(fp_rect
			(start -0.508 0.9398)
			(end 0.508 -0.9398)
			(stroke
				(width 0)
				(type default)
			)
			(fill no)
			(layer "F.Fab")
		)
		(pad "1" smd custom
			(at 0 -0.4445 90)
			(size 0.1397 0.1397)
			(layers "F.Cu" "F.Mask" "F.Paste")
			(net "P1V8_E")
			(options
				(clearance outline)
				(anchor circle)
			)
			(primitives
				(gr_poly
					(pts
						(arc
							(start -0.1778 -0.2794)
							(mid -0.249642 -0.249642)
							(end -0.2794 -0.1778)
						)
						(arc
							(start -0.2794 0.1778)
							(mid -0.249642 0.249642)
							(end -0.1778 0.2794)
						)
						(arc
							(start 0.1778 0.2794)
							(mid 0.249642 0.249642)
							(end 0.2794 0.1778)
						)
						(arc
							(start 0.2794 -0.1778)
							(mid 0.249642 -0.249642)
							(end 0.1778 -0.2794)
						)
					)
					(width 0)
					(fill yes)
				)
			)
		)
		(pad "2" smd custom
			(at 0 0.4445 90)
			(size 0.1397 0.1397)
			(layers "F.Cu" "F.Mask" "F.Paste")
			(net "SDB_UART_EN")
			(options
				(clearance outline)
				(anchor circle)
			)
			(primitives
				(gr_poly
					(pts
						(arc
							(start -0.1778 -0.2794)
							(mid -0.249642 -0.249642)
							(end -0.2794 -0.1778)
						)
						(arc
							(start -0.2794 0.1778)
							(mid -0.249642 0.249642)
							(end -0.1778 0.2794)
						)
						(arc
							(start 0.1778 0.2794)
							(mid 0.249642 0.249642)
							(end 0.2794 0.1778)
						)
						(arc
							(start 0.2794 -0.1778)
							(mid 0.249642 -0.249642)
							(end 0.1778 -0.2794)
						)
					)
					(width 0)
					(fill yes)
				)
			)
		)
	)
	(footprint ""
		(layer "F.Cu")
		(at 106.31297 -76.454)
		(property "Reference" "SR867"
			(at 0 0 0)
			(layer "F.SilkS")
			(hide yes)
			(effects
				(font
					(size 1.27 1.27)
				)
			)
		)
		(property "Value" "0R2J-2-GP"
			(at 0.064008 -3.993896 0)
			(unlocked yes)
			(layer "F.Fab")
			(hide yes)
			(effects
				(font
					(size 1.016 1.016)
					(thickness 0.1524)
				)
			)
		)
		(property "Device Type" "R402H16"
			(at 0.064008 -5.517896 0)
			(unlocked yes)
			(layer "F.Fab")
			(hide yes)
			(effects
				(font
					(size 1.016 1.016)
					(thickness 0.1524)
				)
			)
		)
		(duplicate_pad_numbers_are_jumpers no)
		(fp_line
			(start -0.508 -0.9398)
			(end -0.508 0.9398)
			(stroke
				(width 0.1524)
				(type default)
			)
			(layer "F.SilkS")
		)
		(fp_line
			(start 0.508 -0.9398)
			(end -0.508 -0.9398)
			(stroke
				(width 0.1524)
				(type default)
			)
			(layer "F.SilkS")
		)
		(fp_rect
			(start -0.508 0.9398)
			(end 0.508 -0.9398)
			(stroke
				(width 0)
				(type default)
			)
			(fill no)
			(layer "F.CrtYd")
		)
		(fp_rect
			(start -0.508 0.9398)
			(end 0.508 -0.9398)
			(stroke
				(width 0)
				(type default)
			)
			(fill no)
			(layer "F.Fab")
		)
		(pad "1" smd custom
			(at 0 -0.4445)
			(size 0.1397 0.1397)
			(layers "F.Cu" "F.Mask" "F.Paste")
			(net "LSI_TRST_N")
			(options
				(clearance outline)
				(anchor circle)
			)
			(primitives
				(gr_poly
					(pts
						(arc
							(start -0.1778 -0.2794)
							(mid -0.249642 -0.249642)
							(end -0.2794 -0.1778)
						)
						(arc
							(start -0.2794 0.1778)
							(mid -0.249642 0.249642)
							(end -0.1778 0.2794)
						)
						(arc
							(start 0.1778 0.2794)
							(mid 0.249642 0.249642)
							(end 0.2794 0.1778)
						)
						(arc
							(start 0.2794 -0.1778)
							(mid 0.249642 -0.249642)
							(end 0.1778 -0.2794)
						)
					)
					(width 0)
					(fill yes)
				)
			)
		)
		(pad "2" smd custom
			(at 0 0.4445)
			(size 0.1397 0.1397)
			(layers "F.Cu" "F.Mask" "F.Paste")
			(net "JTAG_EXP_IOC_RST")
			(options
				(clearance outline)
				(anchor circle)
			)
			(primitives
				(gr_poly
					(pts
						(arc
							(start -0.1778 -0.2794)
							(mid -0.249642 -0.249642)
							(end -0.2794 -0.1778)
						)
						(arc
							(start -0.2794 0.1778)
							(mid -0.249642 0.249642)
							(end -0.1778 0.2794)
						)
						(arc
							(start 0.1778 0.2794)
							(mid 0.249642 0.249642)
							(end 0.2794 0.1778)
						)
						(arc
							(start 0.2794 -0.1778)
							(mid 0.249642 -0.249642)
							(end 0.1778 -0.2794)
						)
					)
					(width 0)
					(fill yes)
				)
			)
		)
	)
	(footprint ""
		(layer "F.Cu")
		(at 318.008 -181.864 -90)
		(property "Reference" "R338"
			(at 0 0 270)
			(layer "F.SilkS")
			(hide yes)
			(effects
				(font
					(size 1.27 1.27)
				)
			)
		)
		(property "Value" "2K74R3F-GP"
			(at -0.0254 -2.5146 270)
			(unlocked yes)
			(layer "F.Fab")
			(hide yes)
			(effects
				(font
					(size 1.016 1.016)
					(thickness 0.1524)
				)
			)
		)
		(property "Device Type" "R603H22"
			(at -0.0254 -4.0386 270)
			(unlocked yes)
			(layer "F.Fab")
			(hide yes)
			(effects
				(font
					(size 1.016 1.016)
					(thickness 0.1524)
				)
			)
		)
		(duplicate_pad_numbers_are_jumpers no)
		(fp_line
			(start -0.4826 0)
			(end -0.2032 0)
			(stroke
				(width 0.2032)
				(type default)
			)
			(layer "F.SilkS")
		)
		(fp_line
			(start 0.2032 0)
			(end 0.4826 0)
			(stroke
				(width 0.2032)
				(type default)
			)
			(layer "F.SilkS")
		)
		(fp_rect
			(start -0.5842 1.3335)
			(end 0.5842 -1.3335)
			(stroke
				(width 0)
				(type default)
			)
			(fill no)
			(layer "F.CrtYd")
		)
		(fp_rect
			(start -0.5842 1.3335)
			(end 0.5842 -1.3335)
			(stroke
				(width 0)
				(type default)
			)
			(fill no)
			(layer "F.Fab")
		)
		(pad "1" smd custom
			(at 0 -0.762 270)
			(size 0.2159 0.2159)
			(layers "F.Cu" "F.Mask" "F.Paste")
			(net "GND")
			(options
				(clearance outline)
				(anchor circle)
			)
			(primitives
				(gr_poly
					(pts
						(arc
							(start -0.3302 -0.4318)
							(mid -0.402042 -0.402042)
							(end -0.4318 -0.3302)
						)
						(arc
							(start -0.4318 0.3302)
							(mid -0.402042 0.402042)
							(end -0.3302 0.4318)
						)
						(arc
							(start 0.3302 0.4318)
							(mid 0.402042 0.402042)
							(end 0.4318 0.3302)
						)
						(arc
							(start 0.4318 -0.3302)
							(mid 0.402042 -0.402042)
							(end 0.3302 -0.4318)
						)
					)
					(width 0)
					(fill yes)
				)
			)
		)
		(pad "2" smd custom
			(at 0 0.762 270)
			(size 0.2159 0.2159)
			(layers "F.Cu" "F.Mask" "F.Paste")
			(net "DACRSET")
			(options
				(clearance outline)
				(anchor circle)
			)
			(primitives
				(gr_poly
					(pts
						(arc
							(start -0.3302 -0.4318)
							(mid -0.402042 -0.402042)
							(end -0.4318 -0.3302)
						)
						(arc
							(start -0.4318 0.3302)
							(mid -0.402042 0.402042)
							(end -0.3302 0.4318)
						)
						(arc
							(start 0.3302 0.4318)
							(mid 0.402042 0.402042)
							(end 0.4318 0.3302)
						)
						(arc
							(start 0.4318 -0.3302)
							(mid 0.402042 -0.402042)
							(end 0.3302 -0.4318)
						)
					)
					(width 0)
					(fill yes)
				)
			)
		)
	)
)
